# TIMECARD (Time Appliance Project (Time Card)) — schematic netlist excerpt (pin names and nets, part order shuffled) for the footprints in the layout excerpt that follows; sources: Cadence DE-HDL packaged netlist, KiCad conversion of R4006-B0001-02_R01.brd

R151  RESISTOR  4.7KOHM 1%  pkg SMC_0402R_H016  page 16 : \1\ = XP3R3V_FPGA ; \2\ = UNNAMED_5_PCA9546APWTSSOP16_I_2
L35  FERRITEBEAD  120OHM 25%  pkg SMC_0603R_H030  page 14 : \1\ = FPGA_MGTAVTT ; \2\ = XP1R2V_FPGA

(kicad_pcb
	(version 20260206)
	(generator "pcbnew")
	(generator_version "10.0")
	(general
		(thickness 1.6)
		(legacy_teardrops no)
	)
	(paper "A4")
	(title_block
		(title "timecard-production-celestica-r4006 — R4006-B0001-02_R01.brd")
		(comment 1 "Time Appliance Project (Time Card) / footprints 847-848 of 1113")
	)
	(layers
		(0 "F.Cu" signal "TOP")
		(4 "In1.Cu" signal "L02_GND1")
		(6 "In2.Cu" signal "L03_SIG1")
		(8 "In3.Cu" signal "L04_GND2")
		(10 "In4.Cu" signal "L05_VCC1")
		(12 "In5.Cu" signal "L06_VCC2")
		(14 "In6.Cu" signal "L07_GND3")
		(16 "In7.Cu" signal "L08_SIG2")
		(18 "In8.Cu" signal "L09_GND4")
		(2 "B.Cu" signal "BOTTOM")
		(9 "F.Adhes" user "F.Adhesive")
		(11 "B.Adhes" user "B.Adhesive")
		(13 "F.Paste" user "Package Geometry/Pastemask Top")
		(15 "B.Paste" user "Package Geometry/Pastemask Bottom")
		(5 "F.SilkS" user "Ref Des/Silkscreen Top")
		(7 "B.SilkS" user "Ref Des/Silkscreen Bottom")
		(1 "F.Mask" user "Board Geometry/Soldermask Top")
		(3 "B.Mask" user "Board Geometry/Soldermask Bottom")
		(17 "Dwgs.User" user "User.Drawings")
		(19 "Cmts.User" user "User.Comments")
		(21 "Eco1.User" user "User.Eco1")
		(23 "Eco2.User" user "User.Eco2")
		(25 "Edge.Cuts" user "Board Geometry/Outline")
		(27 "Margin" user)
		(31 "F.CrtYd" user "Package Geometry/Place Bound Top")
		(29 "B.CrtYd" user "Package Geometry/Place Bound Bottom")
		(35 "F.Fab" user "Ref Des/Assembly Top")
		(33 "B.Fab" user "Ref Des/Assembly Bottom")
	)
	(footprint ""
		(layer "B.Cu")
		(at 92.583 -35.433)
		(property "Reference" "L35"
			(at 1.2065 1.43637 0)
			(unlocked yes)
			(layer "B.SilkS")
			(effects
				(font
					(size 0.7874 0.5842)
					(thickness 0.1524)
				)
				(justify left mirror)
			)
		)
		(property "Value" "VAL*"
			(at 0.9398 3.70967 0)
			(unlocked yes)
			(layer "B.Fab")
			(hide yes)
			(effects
				(font
					(size 0.7874 0.5842)
					(thickness 0.1524)
				)
				(justify left mirror)
			)
		)
		(property "Device Type" "FERRITEBEAD-G191-10100-01,120OA"
			(at 0.9906 1.22047 0)
			(unlocked yes)
			(layer "B.Fab")
			(hide yes)
			(effects
				(font
					(size 0.7874 0.5842)
					(thickness 0.1524)
				)
				(justify left mirror)
			)
		)
		(property "User Part Number" "PARTNUM*"
			(at 2.54 2.46507 0)
			(unlocked yes)
			(layer "Cmts.User")
			(hide yes)
			(effects
				(font
					(size 0.7874 0.5842)
					(thickness 0.1524)
				)
				(justify left mirror)
			)
		)
		(property "Tolerance" "TOL*"
			(at 0.9906 5.00507 0)
			(unlocked yes)
			(layer "Cmts.User")
			(hide yes)
			(effects
				(font
					(size 0.7874 0.5842)
					(thickness 0.1524)
				)
				(justify left mirror)
			)
		)
		(duplicate_pad_numbers_are_jumpers no)
		(fp_line
			(start -1.3208 -0.7112)
			(end -1.3208 0.7112)
			(stroke
				(width 0.1)
				(type default)
			)
			(layer "B.SilkS")
		)
		(fp_line
			(start -1.3208 0.7112)
			(end 1.3208 0.7112)
			(stroke
				(width 0.1)
				(type default)
			)
			(layer "B.SilkS")
		)
		(fp_line
			(start 1.3208 -0.7112)
			(end -1.3208 -0.7112)
			(stroke
				(width 0.1)
				(type default)
			)
			(layer "B.SilkS")
		)
		(fp_line
			(start 1.3208 0.7112)
			(end 1.3208 -0.7112)
			(stroke
				(width 0.1)
				(type default)
			)
			(layer "B.SilkS")
		)
		(fp_rect
			(start 1.3208 0.7112)
			(end -1.3208 -0.7112)
			(stroke
				(width 0)
				(type default)
			)
			(fill no)
			(layer "B.CrtYd")
		)
		(fp_line
			(start -0.8128 -0.4572)
			(end -0.8128 0.4572)
			(stroke
				(width 0.1)
				(type default)
			)
			(layer "B.Fab")
		)
		(fp_line
			(start -0.8128 0.4572)
			(end 0.8128 0.4572)
			(stroke
				(width 0.1)
				(type default)
			)
			(layer "B.Fab")
		)
		(fp_line
			(start 0.8128 -0.4572)
			(end -0.8128 -0.4572)
			(stroke
				(width 0.1)
				(type default)
			)
			(layer "B.Fab")
		)
		(fp_line
			(start 0.8128 0.4572)
			(end 0.8128 -0.4572)
			(stroke
				(width 0.1)
				(type default)
			)
			(layer "B.Fab")
		)
		(pad "1" smd rect
			(at 0.6858 0 180)
			(size 0.762 0.8636)
			(layers "B.Cu" "B.Mask" "B.Paste")
			(net "FPGA_MGTAVTT")
		)
		(pad "2" smd rect
			(at -0.6858 0 180)
			(size 0.762 0.8636)
			(layers "B.Cu" "B.Mask" "B.Paste")
			(net "XP1R2V_FPGA")
		)
		(zone
			(layer "B.Cu")
			(hatch none 0.5)
			(connect_pads
				(clearance 0)
			)
			(min_thickness 0.25)
			(keepout
				(tracks not_allowed)
				(vias allowed)
				(pads allowed)
				(copperpour not_allowed)
				(footprints allowed)
			)
			(placement
				(enabled no)
				(sheetname "")
			)
			(fill
				(thermal_gap 0.5)
				(thermal_bridge_width 0.5)
				(island_removal_mode 0)
			)
			(polygon
				(pts
					(xy 92.7354 -34.9758) (xy 92.7354 -35.8902) (xy 92.4306 -35.8902) (xy 92.4306 -34.9758)
				)
			)
		)
		(zone
			(layer "B.Cu")
			(hatch none 0.5)
			(connect_pads
				(clearance 0)
			)
			(min_thickness 0.25)
			(keepout
				(tracks allowed)
				(vias not_allowed)
				(pads allowed)
				(copperpour not_allowed)
				(footprints allowed)
			)
			(placement
				(enabled no)
				(sheetname "")
			)
			(fill
				(thermal_gap 0.5)
				(thermal_bridge_width 0.5)
				(island_removal_mode 0)
			)
			(polygon
				(pts
					(xy 92.7354 -34.9758) (xy 92.7354 -35.8902) (xy 92.4306 -35.8902) (xy 92.4306 -34.9758)
				)
			)
		)
	)
	(footprint ""
		(layer "B.Cu")
		(at 77.3938 -85.09)
		(property "Reference" "R151"
			(at -1.1938 -2.24663 0)
			(unlocked yes)
			(layer "B.SilkS")
			(effects
				(font
					(size 0.7874 0.5842)
					(thickness 0.1524)
				)
				(justify mirror)
			)
		)
		(property "Value" "VAL*"
			(at -0.02032 2.13233 0)
			(unlocked yes)
			(layer "B.Fab")
			(hide yes)
			(effects
				(font
					(size 0.7874 0.5842)
					(thickness 0.1524)
				)
				(justify mirror)
			)
		)
		(property "Tolerance" "TOL*"
			(at -0.044704 3.05435 0)
			(unlocked yes)
			(layer "Cmts.User")
			(hide yes)
			(effects
				(font
					(size 0.7874 0.5842)
					(thickness 0.1524)
				)
				(justify mirror)
			)
		)
		(property "User Part Number" "PARTNUM*"
			(at -0.02032 4.024884 0)
			(unlocked yes)
			(layer "Cmts.User")
			(hide yes)
			(effects
				(font
					(size 0.7874 0.5842)
					(thickness 0.1524)
				)
				(justify mirror)
			)
		)
		(property "Device Type" "RESISTOR-G155-14701-01,4.7KOHMA"
			(at -0.008382 1.210564 0)
			(unlocked yes)
			(layer "B.Fab")
			(hide yes)
			(effects
				(font
					(size 0.7874 0.5842)
					(thickness 0.1524)
				)
				(justify mirror)
			)
		)
		(duplicate_pad_numbers_are_jumpers no)
		(fp_line
			(start -1.143 -0.5588)
			(end 1.143 -0.5588)
			(stroke
				(width 0.1)
				(type default)
			)
			(layer "B.SilkS")
		)
		(fp_line
			(start -1.143 0.5588)
			(end -1.143 -0.5588)
			(stroke
				(width 0.1)
				(type default)
			)
			(layer "B.SilkS")
		)
		(fp_line
			(start 1.143 -0.5588)
			(end 1.143 0.5588)
			(stroke
				(width 0.1)
				(type default)
			)
			(layer "B.SilkS")
		)
		(fp_line
			(start 1.143 0.5588)
			(end -1.143 0.5588)
			(stroke
				(width 0.1)
				(type default)
			)
			(layer "B.SilkS")
		)
		(fp_rect
			(start 1.143 -0.5588)
			(end -1.143 0.5588)
			(stroke
				(width 0)
				(type default)
			)
			(fill no)
			(layer "B.CrtYd")
		)
		(fp_line
			(start -0.508 -0.3048)
			(end 0.508 -0.3048)
			(stroke
				(width 0.1)
				(type default)
			)
			(layer "B.Fab")
		)
		(fp_line
			(start -0.508 0.3048)
			(end -0.508 -0.3048)
			(stroke
				(width 0.1)
				(type default)
			)
			(layer "B.Fab")
		)
		(fp_line
			(start 0.508 -0.3048)
			(end 0.508 0.3048)
			(stroke
				(width 0.1)
				(type default)
			)
			(layer "B.Fab")
		)
		(fp_line
			(start 0.508 0.3048)
			(end -0.508 0.3048)
			(stroke
				(width 0.1)
				(type default)
			)
			(layer "B.Fab")
		)
		(pad "1" smd rect
			(at 0.5334 0 180)
			(size 0.7112 0.6096)
			(layers "B.Cu" "B.Mask" "B.Paste")
			(net "XP3R3V_FPGA")
		)
		(pad "2" smd rect
			(at -0.5334 0 180)
			(size 0.7112 0.6096)
			(layers "B.Cu" "B.Mask" "B.Paste")
			(net "UNNAMED_5_PCA9546APWTSSOP16_I_2")
		)
		(zone
			(layer "B.Cu")
			(hatch none 0.5)
			(connect_pads
				(clearance 0)
			)
			(min_thickness 0.25)
			(keepout
				(tracks allowed)
				(vias not_allowed)
				(pads allowed)
				(copperpour not_allowed)
				(footprints allowed)
			)
			(placement
				(enabled no)
				(sheetname "")
			)
			(fill
				(thermal_gap 0.5)
				(thermal_bridge_width 0.5)
				(island_removal_mode 0)
			)
			(polygon
				(pts
					(xy 77.47 -85.3948) (xy 77.3176 -85.3948) (xy 77.3176 -84.7852) (xy 77.47 -84.7852)
				)
			)
		)
	)
)
